FILE_TYPE = CONNECTIVITY;
{Allegro Design Entry HDL 16.6-p007 (v16-6-112F) 10/10/2012}
"PAGE_NUMBER" = 235;
0"NC";
1"P3V3_STBY\g";
2"GND\g";
3"GND\g";
4"GND\g";
5"GND\g";
6"P3V3_STBY\g";
7"GND\g";
8"GND\g";
9"GND\g";
10"GND\g";
11"GND\g";
12"VR_FET_SW_P12V_STBY_PVDDQ_DEF\g";
13"GND\g";
14"GND\g";
15"VR_PVNN_PCH_AIREF1";
16"VID_PCH_CORE_PVNN_AUX_VID_0";
17"ISENSE_PVNN_PCH_PH1_IMON";
18"VR_PVNN_PCH_XADDR1";
19"VSENSE_P1V05_PCH_STBY_AVSN";
20"SMB_VR_STBY_LVC3_SDA";
21"SMB_VR_STBY_LVC3_SCL";
22"VR_P1V05_PCH_BIREF1";
23"ISENSE_P1V05_PCH_STBY_PH1_IMON";
24"A_TSENSE_P1V05_PCH_STBY_TMON";
25"VR_P1V05_PCH_STBY_AVSP";
26"VSENSE_PVNN_PCH_STBY_AVSN";
27"VR_PVNN_PCH_XADDR2";
28"PU_PVNN_PCH_VCLK";
29"VR_PVNN_PCH_VREN";
30"VR_PVNN_P1V05_PCH_VD12";
31"A_TSENSE_PVNN_PCH_TMON";
32"VR_PVNN_PCH_VINSEN";
33"VSENSE_PVNN_PCH_STBY_AVSP";
34"VSENSE_P1V05_PCH_STBY_AVSP";
35"PU_PVNN_PCH_VDIO";
36"VR_PVNN_PCH_AVSP";
37"VR_P1V05_PCH_STBY_PWM1";
38"VID_PCH_CORE_PVNN_AUX_VID_1";
39"PU_PVNN_PCH_PINALRT_N";
40"PWRGD_P1V8_PCH_STBY";
41"IRQ_PVNN_PCH_VRHOT_N";
42"VR_PVNN_P1V05_PCH_VD12";
43"PU_VR_PVNN_PCH_FAULT1";
44"PWRGD_PVNN_PCH_R";
45"VR_PVNN_PCH_PWM1";
46"PWRGD_PVNN_P1V05_PCH";
47"VR_PVNN_PCH_VDD";
48"VR_PVNN_PCH_VINSEN";
%"P3V3_STBY"
"1","(-8400,5300)","0","mstr_symbols","I135";
;
SIZE"1B"
CDS_LIB"mstr_symbols"
VOLTAGE"3.3V"
BODY_TYPE"PLUMBING"
HDL_POWER"P3V3_STBY";
"G\NAC"1;
%"CAP_A"
"1","(-8800,1975)","0","dev_discrete","I143";
;
LOCATION"C8A7"
PART_NUMBER"D97712-004"
PACK_TYPE"0402V"
MATERIAL"X6S"
VALUE"1.0UF"
TOLERANCE"10%"
VOLTAGE"6.3V"
CDS_LIB"dev_discrete"
CDS_LOCATION"C8A7"
CDS_SEC"1"
SEC_TYPE"0402V"
SEC"1"
ROOM"PVNN_PCH_STBY";
"B"
$PN"2"2;
"A"
$PN"1"42;
%"GND"
"1","(-8800,1750)","0","mstr_symbols","I144";
;
HDL_POWER"GND"
BODY_TYPE"PLUMBING"
ROOM"PVNN_PCH_STBY"
SIZE"1B"
VOLTAGE"0"
CDS_LIB"mstr_symbols";
"A\NAC"2;
%"CAP_A"
"1","(-9200,1975)","0","dev_discrete","I145";
;
VOLTAGE"16V"
TOLERANCE"10%"
PART_NUMBER"A36096-030"
VALUE"0.1UF"
LOCATION"C8A8"
PACK_TYPE"0402V"
MATERIAL"X7R"
CDS_LIB"dev_discrete"
ROOM"PVNN_PCH_STBY"
CDS_LOCATION"C8A8"
CDS_SEC"1"
SEC_TYPE"0402V"
SEC"1";
"B"
$PN"2"3;
"A"
$PN"1"42;
%"GND"
"1","(-9200,1775)","0","mstr_symbols","I146";
;
HDL_POWER"GND"
BODY_TYPE"PLUMBING"
ROOM"PVNN_PCH_STBY"
SIZE"1B"
VOLTAGE"0"
CDS_LIB"mstr_symbols";
"A\NAC"3;
%"RES"
"1","(-7100,4500)","0","mstr_discrete","I147";
;
CDS_SEC"1"
LOCATION"R2L16"
PACK_TYPE"0402"
WATTAGE"1/16W"
TOLERANCE"1.0%"
MATERIAL"CHIP"
VALUE"22.1"
PART_NUMBER"G21796-250"
CDS_LIB"mstr_discrete"
CDS_LOCATION"R2L16"
ROOM"PVNN_PCH_STBY"
SEC_TYPE"0402"
SEC"1";
"B"
$PN"2"46;
"A"
$PN"1"44;
%"RES"
"2","(-8400,4950)","0","mstr_discrete","I148";
;
CDS_SEC"1"
CDS_LOCATION"R2L24"
PACK_TYPE"0402"
PART_NUMBER"G21796-311"
MATERIAL"EMPTY"
LOCATION"R2L24"
TOLERANCE"1.0%"
WATTAGE"1/16W"
VALUE"2.26K"
ROOM"PVNN_PCH_STBY"
CDS_LIB"mstr_discrete"
SEC"1"
SEC_TYPE"0402";
"A"
$PN"1"1;
"B"
$PN"2"43;
%"RES"
"2","(-9100,4950)","0","mstr_discrete","I149";
;
CDS_SEC"1"
PACK_TYPE"0402"
MATERIAL"CHIP"
WATTAGE"1/16W"
TOLERANCE"1%"
VALUE"1.00K"
LOCATION"R8A6"
PART_NUMBER"G21796-026"
SEC_TYPE"0402"
ROOM"PVNN_PCH_STBY"
SEC"1"
CDS_LIB"mstr_discrete"
CDS_LOCATION"R8A6";
"A"
$PN"1"1;
"B"
$PN"2"44;
%"CAP_A"
"1","(-9750,5075)","0","dev_discrete","I151";
;
LOCATION"C2L8"
PART_NUMBER"D97712-004"
VOLTAGE"6.3V"
VALUE"1.0UF"
TOLERANCE"10%"
MATERIAL"X6S"
PACK_TYPE"0402V"
CDS_LIB"dev_discrete"
ROOM"PVNN_PCH_STBY"
SEC"1"
SEC_TYPE"0402V"
CDS_LOCATION"C2L8"
CDS_SEC"1";
"B"
$PN"2"4;
"A"
$PN"1"47;
%"GND"
"1","(-9750,4875)","0","mstr_symbols","I152";
;
HDL_POWER"GND"
BODY_TYPE"PLUMBING"
ROOM"PVNN_PCH_STBY"
VOLTAGE"0"
CDS_LIB"mstr_symbols"
SIZE"1B";
"A\NAC"4;
%"CAP"
"1","(-12475,2075)","0","mstr_discrete","I153";
;
CDS_SEC"1"
TOLERANCE"10%"
LOCATION"C2L2"
MATERIAL"X7R"
PACK_TYPE"0402LF"
PART_NUMBER"A36096-050"
VOLTAGE"50V"
VALUE"220PF"
CDS_LIB"mstr_discrete"
CDS_LOCATION"C2L2"
ROOM"PVNN_PCH_STBY"
NO_XNET_CONNECTION"1"
SEC"1"
SEC_TYPE"0402LF";
"A"
$PN"1"25;
"B"
$PN"2"19;
%"RES"
"1","(-12675,2225)","0","mstr_discrete","I154";
;
CDS_SEC"1"
LOCATION"R2L8"
WATTAGE"1/10W"
VALUE"10.0"
TOLERANCE"1%"
MATERIAL"CHIP"
PACK_TYPE"0603"
PART_NUMBER"G22026-041"
CDS_LIB"mstr_discrete"
CDS_LOCATION"R2L8"
SEC_TYPE"0603"
SEC"1"
ROOM"PVNN_PCH_STBY";
"B"
$PN"2"25;
"A"
$PN"1"34;
%"GND"
"1","(-8900,2800)","0","mstr_symbols","I155";
;
HDL_POWER"GND"
BODY_TYPE"PLUMBING"
ROOM"PVNN_PCH_STBY"
SIZE"1B"
CDS_LIB"mstr_symbols"
VOLTAGE"0";
"A\NAC"5;
%"P3V3_STBY"
"1","(-10450,5750)","0","mstr_symbols","I158";
;
HDL_POWER"P3V3_STBY"
BODY_TYPE"PLUMBING"
CDS_LIB"mstr_symbols"
SIZE"1B"
VOLTAGE"3.3V";
"G\NAC"6;
%"RES"
"2","(-10450,5425)","0","mstr_discrete","I159";
;
CDS_SEC"1"
WATTAGE"1/16W"
MATERIAL"CHIP"
PACK_TYPE"0402"
LOCATION"R2L14"
VALUE"0.0"
TOLERANCE"5%"
PART_NUMBER"G21497-005"
CDS_LIB"mstr_discrete"
CDS_LOCATION"R2L14"
SEC"1"
ROOM"PVNN_PCH_STBY"
SEC_TYPE"0402";
"A"
$PN"1"6;
"B"
$PN"2"47;
%"RES"
"2","(-12325,5500)","0","mstr_discrete","I165";
;
CDS_SEC"1"
WATTAGE"1/16W"
PACK_TYPE"0402"
LOCATION"R8A4"
TOLERANCE"1%"
VALUE"100.0K"
MATERIAL"CHIP"
PART_NUMBER"G21796-160"
CDS_LOCATION"R8A4"
CDS_LIB"mstr_discrete"
ROOM"PVNN_PCH_STBY"
SEC"1"
SEC_TYPE"0402";
"A"
$PN"1"12;
"B"
$PN"2"48;
%"RES"
"2","(-12325,5175)","0","mstr_discrete","I166";
;
CDS_SEC"1"
PACK_TYPE"0402"
PART_NUMBER"G21796-003"
VALUE"1.5K"
MATERIAL"CHIP"
LOCATION"R2L10"
TOLERANCE"1%"
WATTAGE"1/16W"
CDS_LOCATION"R2L10"
CDS_LIB"mstr_discrete"
ROOM"PVNN_PCH_STBY"
SEC"1"
SEC_TYPE"0402";
"A"
$PN"1"48;
"B"
$PN"2"9;
%"CAP_A"
"1","(-10150,5075)","0","dev_discrete","I169";
;
MATERIAL"X7R"
TOLERANCE"10%"
VOLTAGE"16V"
VALUE"0.1UF"
LOCATION"C2L11"
PACK_TYPE"0402V"
PART_NUMBER"A36096-030"
CDS_LIB"dev_discrete"
ROOM"PVNN_PCH_STBY"
CDS_LOCATION"C2L11"
CDS_SEC"1"
SEC_TYPE"0402V"
SEC"1";
"B"
$PN"2"7;
"A"
$PN"1"47;
%"GND"
"1","(-10150,4875)","0","mstr_symbols","I170";
;
HDL_POWER"GND"
BODY_TYPE"PLUMBING"
ROOM"PVNN_PCH_STBY"
SIZE"1B"
CDS_LIB"mstr_symbols"
VOLTAGE"0";
"A\NAC"7;
%"GND"
"1","(-10750,1850)","0","mstr_symbols","I178";
;
VOLTAGE"0"
SIZE"1B"
CDS_LIB"mstr_symbols"
ROOM"PVNN_PCH_STBY"
BODY_TYPE"PLUMBING"
HDL_POWER"GND";
"A\NAC"8;
%"GND"
"1","(-12325,4925)","0","mstr_symbols","I181";
;
HDL_POWER"GND"
BODY_TYPE"PLUMBING"
ROOM"PVNN_PCH_STBY"
VOLTAGE"0"
CDS_LIB"mstr_symbols"
SIZE"1B";
"A\NAC"9;
%"GND"
"1","(-12750,4975)","0","mstr_symbols","I183";
;
SIZE"1B"
VOLTAGE"0"
CDS_LIB"mstr_symbols"
ROOM"PVNN_PCH_STBY"
BODY_TYPE"PLUMBING"
HDL_POWER"GND";
"A\NAC"10;
%"CAP"
"1","(-12375,2600)","0","mstr_discrete","I209";
;
CDS_SEC"1"
TOLERANCE"10%"
MATERIAL"X7R"
VOLTAGE"50V"
PACK_TYPE"0402LF"
VALUE"220PF"
LOCATION"C8A2"
PART_NUMBER"A36096-050"
CDS_LIB"mstr_discrete"
CDS_LOCATION"C8A2"
ROOM"PVNN_PCH_STBY"
SEC_TYPE"0402LF"
SEC"1"
NO_XNET_CONNECTION"1";
"A"
$PN"1"36;
"B"
$PN"2"26;
%"RES"
"1","(-12675,2750)","0","mstr_discrete","I210";
;
CDS_SEC"1"
MATERIAL"CHIP"
PACK_TYPE"0402"
PART_NUMBER"G21796-066"
WATTAGE"1/16W"
VALUE"10.0"
TOLERANCE"1%"
LOCATION"R8A1"
ROOM"PVNN_PCH_STBY"
SEC_TYPE"0402"
SEC"1"
CDS_LOCATION"R8A1"
CDS_LIB"mstr_discrete"
NO_XNET_CONNECTION"1";
"B"
$PN"2"36;
"A"
$PN"1"33;
%"RES"
"2","(-8075,4950)","0","mstr_discrete","I216";
;
CDS_SEC"1"
PACK_TYPE"0402"
PART_NUMBER"G21796-026"
TOLERANCE"1%"
WATTAGE"1/16W"
VALUE"1.00K"
LOCATION"R8A5"
MATERIAL"CHIP"
SEC"1"
SEC_TYPE"0402"
CDS_LOCATION"R8A5"
CDS_LIB"mstr_discrete";
"A"
$PN"1"1;
"B"
$PN"2"41;
%"RES"
"2","(-10450,2150)","0","mstr_discrete","I217";
;
CDS_SEC"1"
VALUE"2.67K"
MATERIAL"CHIP"
LOCATION"R8A2"
PACK_TYPE"0402"
PART_NUMBER"G21796-180"
WATTAGE"1/16W"
TOLERANCE"1%"
SEC"1"
SEC_TYPE"0402"
CDS_LOCATION"R8A2"
CDS_LIB"mstr_discrete";
"A"
$PN"1"27;
"B"
$PN"2"8;
%"CAP"
"1","(-8000,4325)","0","mstr_discrete","I218";
;
CDS_SEC"1"
LOCATION"C8A9"
TOLERANCE"10%"
VOLTAGE"50V"
VALUE"1000PF"
PACK_TYPE"0402LF"
PART_NUMBER"A36096-046"
MATERIAL"X7R"
CDS_LIB"mstr_discrete"
CDS_LOCATION"C8A9"
ROOM"PVNN_PCH_STBY"
SEC"1"
SEC_TYPE"0402LF";
"A"
$PN"1"44;
"B"
$PN"2"11;
%"GND"
"1","(-8000,4075)","0","mstr_symbols","I219";
;
HDL_POWER"GND"
BODY_TYPE"PLUMBING"
ROOM"PVNN_PCH_STBY"
SIZE"1B"
CDS_LIB"mstr_symbols"
VOLTAGE"0";
"A\NAC"11;
%"RES"
"1","(-11800,4150)","0","mstr_discrete","I221";
;
CDS_SEC"1"
PART_NUMBER"G21497-005"
LOCATION"R2L17"
PACK_TYPE"0402"
MATERIAL"CHIP"
VALUE"0.0"
TOLERANCE"5%"
WATTAGE"1/16W"
ROOM"PVCCIN_CPU0_VR"
CDS_LOCATION"R2L17"
CDS_LIB"mstr_discrete"
SEC"1"
SEC_TYPE"0402";
"B"
$PN"2"29;
"A"
$PN"1"40;
%"RES"
"2","(-11175,5075)","0","mstr_discrete","I222";
;
CDS_SEC"1"
WATTAGE"1/16W"
TOLERANCE"1%"
VALUE"100.0K"
LOCATION"R8A7"
MATERIAL"EMPTY"
PACK_TYPE"0402"
PART_NUMBER"G21796-010"
CDS_LIB"mstr_discrete"
ROOM"BMC"
CDS_LOCATION"R8A7"
SEC"1"
SEC_TYPE"0402"
BOM_COST"SM_CONTROLLER";
"A"
$PN"1"6;
"B"
$PN"2"29;
%"VCC_CORE"
"1","(-12325,5750)","0","mstr_symbols","I228";
;
HDL_POWER"VR_FET_SW_P12V_STBY_PVDDQ_DEF"
CDS_LIB"mstr_symbols";
"A"12;
%"PXE1110B"
"1","(-9725,3750)","0","mstr_controller","I229";
;
CDS_SEC"1"
LOCATION"EU8A1"
MATERIAL"IC"
PART_NUMBER"H89187-001"
CDS_LOCATION"EU8A1"
SEC"1"
SEC_TYPE"QFN"
PACK_TYPE"QFN"
CDS_LIB"mstr_controller"
CDS_LMAN_SYM_OUTLINE"-400,850,400,-850";
"AVRRDY"
$PN"9"44;
"PINALRT_N \B"
$PN"12"39;
"THPAD"
$PN"41"5;
"BPWM1"
$PN"3"37;
"APWM1"
$PN"5"45;
"SDA"
$PN"6"20;
"SCL"
$PN"7"21;
"VCLK"
$PN"15"28;
"VDIO"
$PN"16"35;
"RESET_N \B"
$PN"8"0;
"XADDR1"
$PN"36"18;
"XADDR2"
$PN"33"27;
"ATSEN"
$PN"35"31;
"AISEN1"
$PN"22"17;
"AIREF1"
$PN"21"15;
"VDD"
$PN"39"47;
"BTSEN"
$PN"34"24;
"BISEN1"
$PN"26"23;
"BIREF1"
$PN"25"22;
"DNC<0>"
$PN"1"0;
"DNC<1>"
$PN"2"0;
"DNC<2>"
$PN"4"0;
"DNC<4>"
$PN"28"0;
"GND<0>"
$PN"27"5;
"GND<1>"
$PN"23"5;
"VRHOT_N \B"
$PN"11"41;
"VALRT_N \B"
$PN"17"0;
"AVSEN"
$PN"19"36;
"AVREF"
$PN"20"26;
"BVSEN"
$PN"29"25;
"BVREF"
$PN"30"19;
"VINSEN"
$PN"37"32;
"IINSEN"
$PN"38"0;
"VD12"
$PN"40"30;
"DNC<3>"
$PN"24"0;
"MP0"
$PN"13"16;
"MP1"
$PN"14"38;
"MP2"
$PN"18"0;
"MP3"
$PN"31"0;
"MP4"
$PN"32"43;
"AVREN"
$PN"10"29;
%"SC22P50V2JN-4GP"
"1","(-11800,4450)","1","w_hdl","I239";
;
CDS_SEC"1"
$SEC"1"
CDS_LOCATION"CF23"
GROUP"POWER_FAIR"
LOCATION"CF23"
TYPE"NPO"
TOLERANCE"5%"
PACK_SIZE"0402"
ATTRIBUTE"22PF"
VALUE"SC22P50V2JN-4GP"
RATED"50V"
PART_NUMBER"78.22034.1FL"
PACK_TYPE"SMD-BCG"
CDS_LMAN_SYM_OUTLINE"-50,25,50,-25"
CDS_LIB"w_hdl";
"2"
$PN"2"17;
"1"
$PN"1"15;
%"SC22P50V2JN-4GP"
"1","(-11100,2900)","1","w_hdl","I240";
;
CDS_SEC"1"
$SEC"1"
CDS_LOCATION"CF24"
GROUP"POWER_FAIR"
VALUE"SC22P50V2JN-4GP"
ATTRIBUTE"22PF"
TOLERANCE"5%"
LOCATION"CF24"
TYPE"NPO"
RATED"50V"
PACK_SIZE"0402"
PART_NUMBER"78.22034.1FL"
PACK_TYPE"SMD-BCG"
CDS_LMAN_SYM_OUTLINE"-50,25,50,-25"
CDS_LIB"w_hdl";
"2"
$PN"2"23;
"1"
$PN"1"22;
%"RES"
"1","(-11775,4650)","0","mstr_discrete","I241";
;
CDS_SEC"1"
CDS_LOCATION"RF23"
LOCATION"RF23"
VALUE"1.0K"
PACK_TYPE"0402"
PART_NUMBER"G85996-004"
TOLERANCE"0.1%"
WATTAGE"1/16W"
MATERIAL"CHIP"
GROUP"POWER_FAIR"
SEC_TYPE"0402"
SEC"1"
CDS_LIB"mstr_discrete"
ROOM"SB";
"B"
$PN"2"17;
"A"
$PN"1"15;
%"RES"
"1","(-11100,3000)","0","mstr_discrete","I242";
;
CDS_SEC"1"
CDS_LOCATION"RF24"
MATERIAL"CHIP"
VALUE"1.0K"
LOCATION"RF24"
PART_NUMBER"G85996-004"
TOLERANCE"0.1%"
PACK_TYPE"0402"
WATTAGE"1/16W"
GROUP"POWER_FAIR"
SEC"1"
SEC_TYPE"0402"
ROOM"SB"
CDS_LIB"mstr_discrete";
"B"
$PN"2"23;
"A"
$PN"1"22;
%"GND"
"1","(-12200,3500)","0","mstr_symbols","I243";
;
HDL_POWER"GND"
BODY_TYPE"PLUMBING"
CDS_LIB"mstr_symbols"
VOLTAGE"0"
ROOM"PVCCIN_CPU0_VR"
SIZE"1B";
"A\NAC"13;
%"CAP"
"1","(-12200,3700)","0","mstr_discrete","I244";
;
MATERIAL"X7R"
VOLTAGE"50V"
VALUE"220PF"
LOCATION"C4W3"
TOLERANCE"10%"
PACK_TYPE"0402LF"
PART_NUMBER"A36096-050"
CDS_LOCATION"C4W3"
CDS_SEC"1"
CDS_LIB"mstr_discrete"
ROOM"PVCCIN_CPU0_VR"
SEC"1"
SEC_TYPE"0402LF";
"A"
$PN"1"31;
"B"
$PN"2"13;
%"GND"
"1","(-10000,2150)","0","mstr_symbols","I245";
;
HDL_POWER"GND"
BODY_TYPE"PLUMBING"
CDS_LIB"mstr_symbols"
VOLTAGE"0"
ROOM"PVCCIN_CPU0_VR"
SIZE"1B";
"A\NAC"14;
%"CAP"
"1","(-10000,2350)","0","mstr_discrete","I246";
;
PACK_TYPE"0402LF"
PART_NUMBER"A36096-050"
VOLTAGE"50V"
LOCATION"C4W4"
MATERIAL"X7R"
TOLERANCE"10%"
VALUE"220PF"
CDS_LOCATION"C4W4"
CDS_SEC"1"
CDS_LIB"mstr_discrete"
ROOM"PVCCIN_CPU0_VR"
SEC"1"
SEC_TYPE"0402LF";
"A"
$PN"1"24;
"B"
$PN"2"14;
%"RES"
"2","(-11100,4600)","0","mstr_discrete","I247";
;
CDS_SEC"1"
WATTAGE"1/16W"
PART_NUMBER"G21796-026"
TOLERANCE"1%"
MATERIAL"CHIP"
PACK_TYPE"0402"
VALUE"1.00K"
LOCATION"R8W2"
CDS_LOCATION"R8W2"
SEC_TYPE"0402"
ROOM"PVNN_PCH_STBY"
SEC"1"
CDS_LIB"mstr_discrete";
"A"
$PN"1"28;
"B"
$PN"2"30;
%"RES"
"2","(-11800,3750)","0","mstr_discrete","I248";
;
CDS_SEC"1"
TOLERANCE"1%"
VALUE"1.00K"
MATERIAL"CHIP"
PART_NUMBER"G21796-026"
PACK_TYPE"0402"
WATTAGE"1/16W"
LOCATION"R8W3"
CDS_LOCATION"R8W3"
SEC_TYPE"0402"
ROOM"PVNN_PCH_STBY"
SEC"1"
CDS_LIB"mstr_discrete";
"A"
$PN"1"30;
"B"
$PN"2"35;
%"RES"
"2","(-8750,4950)","0","mstr_discrete","I249";
;
CDS_SEC"1"
PART_NUMBER"G21796-026"
TOLERANCE"1%"
WATTAGE"1/16W"
VALUE"1.00K"
LOCATION"R8W8"
MATERIAL"CHIP"
PACK_TYPE"0402"
SEC_TYPE"0402"
ROOM"PVNN_PCH_STBY"
SEC"1"
CDS_LIB"mstr_discrete"
CDS_LOCATION"R8W8";
"A"
$PN"1"1;
"B"
$PN"2"39;
%"RES"
"2","(-7750,4950)","0","mstr_discrete","I252";
;
CDS_SEC"1"
CDS_LOCATION"R2L25"
MATERIAL"CHIP"
VALUE"100.0K"
PART_NUMBER"G21796-010"
PACK_TYPE"0402"
TOLERANCE"1%"
WATTAGE"1/16W"
LOCATION"R2L25"
ROOM"SB"
CDS_LIB"mstr_discrete"
SEC_TYPE"0402"
SEC"1";
"A"
$PN"1"1;
"B"
$PN"2"38;
%"RES"
"2","(-7350,4950)","0","mstr_discrete","I253";
;
CDS_SEC"1"
CDS_LOCATION"R2L26"
PACK_TYPE"0402"
LOCATION"R2L26"
MATERIAL"CHIP"
PART_NUMBER"G21796-010"
WATTAGE"1/16W"
TOLERANCE"1%"
VALUE"100.0K"
ROOM"SB"
CDS_LIB"mstr_discrete"
SEC_TYPE"0402"
SEC"1";
"A"
$PN"1"1;
"B"
$PN"2"16;
%"RES"
"2","(-10750,2150)","0","mstr_discrete","I254";
;
VALUE"4.02K"
PART_NUMBER"G21796-082"
MATERIAL"CHIP"
PACK_TYPE"0402"
TOLERANCE"1%"
WATTAGE"1/16W"
LOCATION"R2L9"
CDS_LOCATION"R2L9"
CDS_SEC"1"
SEC_TYPE"0402"
SEC"1"
ROOM"PVCCIN_CPU0_VR"
CDS_LIB"mstr_discrete";
"A"
$PN"1"18;
"B"
$PN"2"8;
%"CAP_A"
"1","(-12750,5150)","0","dev_discrete","I255";
;
PART_NUMBER"A36096-030"
MATERIAL"X7R"
TOLERANCE"10%"
VOLTAGE"16V"
LOCATION"C8A3"
PACK_TYPE"0402V"
VALUE"0.1UF"
CDS_SEC"1"
SEC"1"
SEC_TYPE"0402V"
ROOM"CPU_FANS"
BOM_COST"SM_THERM"
CDS_LIB"dev_discrete"
CDS_LOCATION"C8A3";
"B"
$PN"2"10;
"A"
$PN"1"48;
END.
